# TIMECARD (Time Appliance Project (Time Card)) — schematic netlist excerpt (pin names and nets, part order shuffled) for the footprints in the layout excerpt that follows; sources: Cadence DE-HDL packaged netlist, KiCad conversion of R4006-B0001-02_R01.brd

GF1  CONN_64P_GF  pkg S_M_EF64_PCIE_P0394_V1  page 9
  \prsnt1*\  = CARD_PRESENT
  P_12V3  = XP12R0V_PCIE
  P_12V5  = XP12R0V_PCIE
  GND2  = SG
  JTAG2  = PCIE_CONN_TCK
  JTAG3  = PCIE_CONN_TDI
  JTAG4  = PCIE_CONN_TDO
  JTAG5  = PCIE_CONN_TMS
  P_3V3_2  = XP3R3V_PCIE
  P_3V3_3  = XP3R3V_PCIE
  \perst*\  = PCIE_CONN_PERST_N
  GND4  = SG
  REFCLK_P  = C_PCIEREFCLKP
  REFCLK_N  = C_PCIEREFCLKN
  GND6  = SG
  PERP0  = C_CPU_RX_PCIE_MGT0_TXP
  PERN0  = C_CPU_RX_PCIE_MGT0_TXN
  GND8  = SG
  RSVD2  = NC
  GND10  = SG
  PERP1  = C_CPU_RX_PCIE_MGT1_TXP
  PERN1  = C_CPU_RX_PCIE_MGT1_TXN
  GND13  = SG
  GND14  = SG
  PERP2  = C_CPU_RX_PCIE_MGT2_TXP
  PERN2  = C_CPU_RX_PCIE_MGT2_TXN
  GND18  = SG
  GND19  = SG
  PERP3  = C_CPU_RX_PCIE_MGT3_TXP
  PERN3  = C_CPU_RX_PCIE_MGT3_TXN
  GND21  = SG
  RSVD4  = NC
  P_12V1  = XP12R0V_PCIE
  P_12V2  = XP12R0V_PCIE
  P_12V4  = XP12R0V_PCIE
  GND1  = SG
  SMCLK  = PCIE_CONN_SMCLK
  SMDAT  = PCIE_CONN_SMDAT
  GND3  = SG
  P_3V3_1  = XP3R3V_PCIE
  JTAG1  = NC
  P_3V3AUX  = XP3R3V_AUX_PCIE
  \wake*\  = NC
  RSVD1  = NC
  GND5  = SG
  PETP0  = CPU_TX_PCIE_MGT_0_RXP
  PETN0  = CPU_TX_PCIE_MGT_0_RXN
  GND7  = SG
  \prsnt2_1*\  = UNNAMED_3_CONN64PGF_I61_PRSNT21
  GND9  = SG
  PETP1  = CPU_TX_PCIE_MGT_1_RXP
  PETN1  = CPU_TX_PCIE_MGT_1_RXN
  GND11  = SG
  GND12  = SG
  PETP2  = CPU_TX_PCIE_MGT_2_RXP
  PETN2  = CPU_TX_PCIE_MGT_2_RXN
  GND15  = SG
  GND17  = SG
  PETP3  = CPU_TX_PCIE_MGT_3_RXP
  PETN3  = CPU_TX_PCIE_MGT_3_RXN
  GND20  = SG
  RSVD3  = NC
  \prsnt2_2*\  = UNNAMED_3_CONN64PGF_I61_PRSNT22
  GND22  = SG

(kicad_pcb
	(version 20260206)
	(generator "pcbnew")
	(generator_version "10.0")
	(general
		(thickness 1.6)
		(legacy_teardrops no)
	)
	(paper "A4")
	(title_block
		(title "timecard-production-celestica-r4006 — R4006-B0001-02_R01.brd")
		(comment 1 "Time Appliance Project (Time Card) / footprint 606 of 1113 (GF1), pads 1-48 of 64")
	)
	(layers
		(0 "F.Cu" signal "TOP")
		(4 "In1.Cu" signal "L02_GND1")
		(6 "In2.Cu" signal "L03_SIG1")
		(8 "In3.Cu" signal "L04_GND2")
		(10 "In4.Cu" signal "L05_VCC1")
		(12 "In5.Cu" signal "L06_VCC2")
		(14 "In6.Cu" signal "L07_GND3")
		(16 "In7.Cu" signal "L08_SIG2")
		(18 "In8.Cu" signal "L09_GND4")
		(2 "B.Cu" signal "BOTTOM")
		(9 "F.Adhes" user "F.Adhesive")
		(11 "B.Adhes" user "B.Adhesive")
		(13 "F.Paste" user "Package Geometry/Pastemask Top")
		(15 "B.Paste" user "Package Geometry/Pastemask Bottom")
		(5 "F.SilkS" user "Ref Des/Silkscreen Top")
		(7 "B.SilkS" user "Ref Des/Silkscreen Bottom")
		(1 "F.Mask" user "Board Geometry/Soldermask Top")
		(3 "B.Mask" user "Board Geometry/Soldermask Bottom")
		(17 "Dwgs.User" user "User.Drawings")
		(19 "Cmts.User" user "User.Comments")
		(21 "Eco1.User" user "User.Eco1")
		(23 "Eco2.User" user "User.Eco2")
		(25 "Edge.Cuts" user "Board Geometry/Outline")
		(27 "Margin" user)
		(31 "F.CrtYd" user "Package Geometry/Place Bound Top")
		(29 "B.CrtYd" user "Package Geometry/Place Bound Bottom")
		(35 "F.Fab" user "Ref Des/Assembly Top")
		(33 "B.Fab" user "Ref Des/Assembly Bottom")
	)
	(footprint ""
		(layer "F.Cu")
		(at 45.649896 -3.500374)
		(property "Reference" "GF1"
			(at 13.786104 -5.350256 0)
			(unlocked yes)
			(layer "F.SilkS")
			(effects
				(font
					(size 0.7874 0.5842)
					(thickness 0.1524)
				)
			)
		)
		(property "Value" ""
			(at 0 0 0)
			(layer "F.Fab")
			(effects
				(font
					(size 1.27 1.27)
				)
			)
		)
		(property "Device Type" "CONN_64P_GF-S_M_EF64_PCIE_P039A"
			(at 19.1262 4.810506 0)
			(unlocked yes)
			(layer "F.Fab")
			(hide yes)
			(effects
				(font
					(size 0.7874 0.5842)
					(thickness 0.1524)
				)
			)
		)
		(property "User Part Number" "PARTNUM*"
			(at 19.1262 5.978906 0)
			(unlocked yes)
			(layer "Cmts.User")
			(hide yes)
			(effects
				(font
					(size 0.7874 0.5842)
					(thickness 0.1524)
				)
			)
		)
		(duplicate_pad_numbers_are_jumpers no)
		(pad "A1" smd rect
			(at 0 -0.4953)
			(size 0.7112 3.2004)
			(layers "F.Cu" "F.Mask" "F.Paste")
			(net "CARD_PRESENT")
		)
		(pad "A2" smd rect
			(at 0.999998 0)
			(size 0.7112 4.191)
			(layers "F.Cu" "F.Mask" "F.Paste")
			(net "XP12R0V_PCIE")
		)
		(pad "A3" smd rect
			(at 1.999996 0)
			(size 0.7112 4.191)
			(layers "F.Cu" "F.Mask" "F.Paste")
			(net "XP12R0V_PCIE")
		)
		(pad "A4" smd rect
			(at 2.999994 0)
			(size 0.7112 4.191)
			(layers "F.Cu" "F.Mask" "F.Paste")
			(net "SG")
		)
		(pad "A5" smd rect
			(at 3.999992 0)
			(size 0.7112 4.191)
			(layers "F.Cu" "F.Mask" "F.Paste")
			(net "PCIE_CONN_TCK")
		)
		(pad "A6" smd rect
			(at 4.99999 0)
			(size 0.7112 4.191)
			(layers "F.Cu" "F.Mask" "F.Paste")
			(net "PCIE_CONN_TDI")
		)
		(pad "A7" smd rect
			(at 5.999988 0)
			(size 0.7112 4.191)
			(layers "F.Cu" "F.Mask" "F.Paste")
			(net "PCIE_CONN_TDO")
		)
		(pad "A8" smd rect
			(at 6.999986 0)
			(size 0.7112 4.191)
			(layers "F.Cu" "F.Mask" "F.Paste")
			(net "PCIE_CONN_TMS")
		)
		(pad "A9" smd rect
			(at 7.999984 0)
			(size 0.7112 4.191)
			(layers "F.Cu" "F.Mask" "F.Paste")
			(net "XP3R3V_PCIE")
		)
		(pad "A10" smd rect
			(at 8.999982 0)
			(size 0.7112 4.191)
			(layers "F.Cu" "F.Mask" "F.Paste")
			(net "XP3R3V_PCIE")
		)
		(pad "A11" smd rect
			(at 9.99998 0)
			(size 0.7112 4.191)
			(layers "F.Cu" "F.Mask" "F.Paste")
			(net "PCIE_CONN_PERST_N")
		)
		(pad "A12" smd rect
			(at 12.999974 0)
			(size 0.7112 4.191)
			(layers "F.Cu" "F.Mask" "F.Paste")
			(net "SG")
		)
		(pad "A13" smd rect
			(at 13.999972 0)
			(size 0.7112 4.191)
			(layers "F.Cu" "F.Mask" "F.Paste")
			(net "C_PCIEREFCLKP")
		)
		(pad "A14" smd rect
			(at 14.99997 0)
			(size 0.7112 4.191)
			(layers "F.Cu" "F.Mask" "F.Paste")
			(net "C_PCIEREFCLKN")
		)
		(pad "A15" smd rect
			(at 15.999968 0)
			(size 0.7112 4.191)
			(layers "F.Cu" "F.Mask" "F.Paste")
			(net "SG")
		)
		(pad "A16" smd rect
			(at 16.999966 0)
			(size 0.7112 4.191)
			(layers "F.Cu" "F.Mask" "F.Paste")
			(net "C_CPU_RX_PCIE_MGT0_TXP")
		)
		(pad "A17" smd rect
			(at 17.999964 0)
			(size 0.7112 4.191)
			(layers "F.Cu" "F.Mask" "F.Paste")
			(net "C_CPU_RX_PCIE_MGT0_TXN")
		)
		(pad "A18" smd rect
			(at 18.999962 0)
			(size 0.7112 4.191)
			(layers "F.Cu" "F.Mask" "F.Paste")
			(net "SG")
		)
		(pad "A19" smd rect
			(at 19.99996 0)
			(size 0.7112 4.191)
			(layers "F.Cu" "F.Mask" "F.Paste")
			(net "Net_752")
		)
		(pad "A20" smd rect
			(at 20.999958 0)
			(size 0.7112 4.191)
			(layers "F.Cu" "F.Mask" "F.Paste")
			(net "SG")
		)
		(pad "A21" smd rect
			(at 21.999956 0)
			(size 0.7112 4.191)
			(layers "F.Cu" "F.Mask" "F.Paste")
			(net "C_CPU_RX_PCIE_MGT1_TXP")
		)
		(pad "A22" smd rect
			(at 22.999954 0)
			(size 0.7112 4.191)
			(layers "F.Cu" "F.Mask" "F.Paste")
			(net "C_CPU_RX_PCIE_MGT1_TXN")
		)
		(pad "A23" smd rect
			(at 23.999952 0)
			(size 0.7112 4.191)
			(layers "F.Cu" "F.Mask" "F.Paste")
			(net "SG")
		)
		(pad "A24" smd rect
			(at 24.99995 0)
			(size 0.7112 4.191)
			(layers "F.Cu" "F.Mask" "F.Paste")
			(net "SG")
		)
		(pad "A25" smd rect
			(at 25.999948 0)
			(size 0.7112 4.191)
			(layers "F.Cu" "F.Mask" "F.Paste")
			(net "C_CPU_RX_PCIE_MGT2_TXP")
		)
		(pad "A26" smd rect
			(at 26.999946 0)
			(size 0.7112 4.191)
			(layers "F.Cu" "F.Mask" "F.Paste")
			(net "C_CPU_RX_PCIE_MGT2_TXN")
		)
		(pad "A27" smd rect
			(at 27.999944 0)
			(size 0.7112 4.191)
			(layers "F.Cu" "F.Mask" "F.Paste")
			(net "SG")
		)
		(pad "A28" smd rect
			(at 28.999942 0)
			(size 0.7112 4.191)
			(layers "F.Cu" "F.Mask" "F.Paste")
			(net "SG")
		)
		(pad "A29" smd rect
			(at 29.99994 0)
			(size 0.7112 4.191)
			(layers "F.Cu" "F.Mask" "F.Paste")
			(net "C_CPU_RX_PCIE_MGT3_TXP")
		)
		(pad "A30" smd rect
			(at 30.999938 0)
			(size 0.7112 4.191)
			(layers "F.Cu" "F.Mask" "F.Paste")
			(net "C_CPU_RX_PCIE_MGT3_TXN")
		)
		(pad "A31" smd rect
			(at 31.999936 0)
			(size 0.7112 4.191)
			(layers "F.Cu" "F.Mask" "F.Paste")
			(net "SG")
		)
		(pad "A32" smd rect
			(at 32.999934 0)
			(size 0.7112 4.191)
			(layers "F.Cu" "F.Mask" "F.Paste")
			(net "Net_750")
		)
		(pad "B1" smd rect
			(at 0 0)
			(size 0.7112 4.191)
			(layers "F.Cu" "F.Mask" "F.Paste")
			(net "XP12R0V_PCIE")
		)
		(pad "B2" smd rect
			(at 0.999998 0)
			(size 0.7112 4.191)
			(layers "F.Cu" "F.Mask" "F.Paste")
			(net "XP12R0V_PCIE")
		)
		(pad "B3" smd rect
			(at 1.999996 0)
			(size 0.7112 4.191)
			(layers "F.Cu" "F.Mask" "F.Paste")
			(net "XP12R0V_PCIE")
		)
		(pad "B4" smd rect
			(at 2.999994 0)
			(size 0.7112 4.191)
			(layers "F.Cu" "F.Mask" "F.Paste")
			(net "SG")
		)
		(pad "B5" smd rect
			(at 3.999992 0)
			(size 0.7112 4.191)
			(layers "F.Cu" "F.Mask" "F.Paste")
			(net "PCIE_CONN_SMCLK")
		)
		(pad "B6" smd rect
			(at 4.99999 0)
			(size 0.7112 4.191)
			(layers "F.Cu" "F.Mask" "F.Paste")
			(net "PCIE_CONN_SMDAT")
		)
		(pad "B7" smd rect
			(at 5.999988 0)
			(size 0.7112 4.191)
			(layers "F.Cu" "F.Mask" "F.Paste")
			(net "SG")
		)
		(pad "B8" smd rect
			(at 6.999986 0)
			(size 0.7112 4.191)
			(layers "F.Cu" "F.Mask" "F.Paste")
			(net "XP3R3V_PCIE")
		)
		(pad "B9" smd rect
			(at 7.999984 0)
			(size 0.7112 4.191)
			(layers "F.Cu" "F.Mask" "F.Paste")
			(net "Net_754")
		)
		(pad "B10" smd rect
			(at 8.999982 0)
			(size 0.7112 4.191)
			(layers "F.Cu" "F.Mask" "F.Paste")
			(net "XP3R3V_AUX_PCIE")
		)
		(pad "B11" smd rect
			(at 9.99998 0)
			(size 0.7112 4.191)
			(layers "F.Cu" "F.Mask" "F.Paste")
			(net "Net_749")
		)
		(pad "B12" smd rect
			(at 12.999974 0)
			(size 0.7112 4.191)
			(layers "F.Cu" "F.Mask" "F.Paste")
			(net "Net_753")
		)
		(pad "B13" smd rect
			(at 13.999972 0)
			(size 0.7112 4.191)
			(layers "F.Cu" "F.Mask" "F.Paste")
			(net "SG")
		)
		(pad "B14" smd rect
			(at 14.99997 0)
			(size 0.7112 4.191)
			(layers "F.Cu" "F.Mask" "F.Paste")
			(net "CPU_TX_PCIE_MGT_0_RXP")
		)
		(pad "B15" smd rect
			(at 15.999968 0)
			(size 0.7112 4.191)
			(layers "F.Cu" "F.Mask" "F.Paste")
			(net "CPU_TX_PCIE_MGT_0_RXN")
		)
		(pad "B16" smd rect
			(at 16.999966 0)
			(size 0.7112 4.191)
			(layers "F.Cu" "F.Mask" "F.Paste")
			(net "SG")
		)
	)
)
